# T6G (Grand Teton) — schematic netlist excerpt (pin names and nets, part order shuffled) for the footprints in the layout excerpt that follows; sources: Cadence DE-HDL packaged netlist, KiCad conversion of 04192023_DAF0TMB3IC0_F0TG_MB_C_brd_V02_OCP.brd

C6544  Q_CAP_DIFFBUS  DIFF BUS_0.22UF 6.3V 20% X6S  pkg C0201  page 286 : \1\ = P5E_CPU0_P1_TX_BUF_C_DN<5> ; \2\ = P5E_CPU0_P1_TX_BUF_DN<5>
R1261  Q_RES  10K 5% CHIP  pkg 0402LF  page 167 : A = P1V8_AUX ; B = FM_SPD_CPU0_SWITCH_CTRL_N
R378  Q_RES  15 1% CHIP  pkg 0402LF  page 13 : A = M_D_CPU0_ALERT_N ; B = M_D_CPU0_ALERT_R_N

(kicad_pcb
	(version 20260206)
	(generator "pcbnew")
	(generator_version "10.0")
	(general
		(thickness 1.6)
		(legacy_teardrops no)
	)
	(paper "A4")
	(title_block
		(title "04192023_DAF0TMB3IC0_F0TG_MB_C_brd_V02_OCP.brd")
		(comment 1 "Grand Teton / footprints 6835-6837 of 8354")
	)
	(layers
		(0 "F.Cu" signal "TOP")
		(4 "In1.Cu" signal "GND")
		(6 "In2.Cu" signal "IN1")
		(8 "In3.Cu" signal "GND1")
		(10 "In4.Cu" signal "IN2")
		(12 "In5.Cu" signal "GND2")
		(14 "In6.Cu" signal "IN3")
		(16 "In7.Cu" signal "GND3")
		(18 "In8.Cu" signal "VCC")
		(20 "In9.Cu" signal "VCC1")
		(22 "In10.Cu" signal "GND4")
		(24 "In11.Cu" signal "IN4")
		(26 "In12.Cu" signal "GND5")
		(28 "In13.Cu" signal "IN5")
		(30 "In14.Cu" signal "GND6")
		(32 "In15.Cu" signal "IN6")
		(34 "In16.Cu" signal "GND7")
		(2 "B.Cu" signal "BOTTOM")
		(9 "F.Adhes" user "F.Adhesive")
		(11 "B.Adhes" user "B.Adhesive")
		(13 "F.Paste" user "Package Geometry/Pastemask Top")
		(15 "B.Paste" user "Package Geometry/Pastemask Bottom")
		(5 "F.SilkS" user "Ref Des/Silkscreen Top")
		(7 "B.SilkS" user "Ref Des/Silkscreen Bottom")
		(1 "F.Mask" user "Board Geometry/Soldermask Top")
		(3 "B.Mask" user "Board Geometry/Soldermask Bottom")
		(17 "Dwgs.User" user "User.Drawings")
		(19 "Cmts.User" user "User.Comments")
		(21 "Eco1.User" user "User.Eco1")
		(23 "Eco2.User" user "User.Eco2")
		(25 "Edge.Cuts" user "Board Geometry/Outline")
		(27 "Margin" user)
		(31 "F.CrtYd" user "Package Geometry/Place Bound Top")
		(29 "B.CrtYd" user "Package Geometry/Place Bound Bottom")
		(35 "F.Fab" user "Ref Des/Assembly Top")
		(33 "B.Fab" user "Ref Des/Assembly Bottom")
	)
	(footprint ""
		(layer "B.Cu")
		(at 320.616326 -416.899344 90)
		(property "Reference" "C6544"
			(at 0 0 90)
			(layer "B.SilkS")
			(hide yes)
			(effects
				(font
					(size 1.27 1.27)
				)
				(justify mirror)
			)
		)
		(property "Value" ""
			(at 0 0 90)
			(layer "B.Fab")
			(effects
				(font
					(size 1.27 1.27)
				)
				(justify mirror)
			)
		)
		(duplicate_pad_numbers_are_jumpers no)
		(fp_line
			(start 0.299974 -0.150114)
			(end -0.299974 -0.150114)
			(stroke
				(width 0.1)
				(type default)
			)
			(layer "B.Fab")
		)
		(fp_line
			(start -0.299974 -0.150114)
			(end -0.299974 0.150114)
			(stroke
				(width 0.1)
				(type default)
			)
			(layer "B.Fab")
		)
		(fp_line
			(start 0.299974 0.150114)
			(end 0.299974 -0.150114)
			(stroke
				(width 0.1)
				(type default)
			)
			(layer "B.Fab")
		)
		(fp_line
			(start -0.299974 0.150114)
			(end 0.299974 0.150114)
			(stroke
				(width 0.1)
				(type default)
			)
			(layer "B.Fab")
		)
		(pad "1" smd rect
			(at 0.2667 0 270)
			(size 0.3048 0.381)
			(layers "B.Cu" "B.Mask" "B.Paste")
			(net "P5E_CPU0_P1_TX_BUF_C_DN<5>")
		)
		(pad "2" smd rect
			(at -0.2667 0 270)
			(size 0.3048 0.381)
			(layers "B.Cu" "B.Mask" "B.Paste")
			(net "P5E_CPU0_P1_TX_BUF_DN<5>")
		)
	)
	(footprint ""
		(layer "B.Cu")
		(at 428.98695 -42.357548 180)
		(property "Reference" "R1261"
			(at 0 0 0)
			(layer "B.SilkS")
			(hide yes)
			(effects
				(font
					(size 1.27 1.27)
				)
				(justify mirror)
			)
		)
		(property "Value" ""
			(at 0 0 0)
			(layer "B.Fab")
			(effects
				(font
					(size 1.27 1.27)
				)
				(justify mirror)
			)
		)
		(duplicate_pad_numbers_are_jumpers no)
		(fp_line
			(start 0.7874 0.4064)
			(end 0.7874 -0.4064)
			(stroke
				(width 0.1524)
				(type default)
			)
			(layer "B.SilkS")
		)
		(fp_line
			(start 0.7874 -0.4064)
			(end -0.7874 -0.4064)
			(stroke
				(width 0.1524)
				(type default)
			)
			(layer "B.SilkS")
		)
		(fp_line
			(start -0.7874 0.4064)
			(end 0.7874 0.4064)
			(stroke
				(width 0.1524)
				(type default)
			)
			(layer "B.SilkS")
		)
		(fp_line
			(start -0.7874 -0.4064)
			(end -0.7874 0.4064)
			(stroke
				(width 0.1524)
				(type default)
			)
			(layer "B.SilkS")
		)
		(fp_line
			(start 0.67945 0.3048)
			(end 0.67945 -0.305054)
			(stroke
				(width 0.1)
				(type default)
			)
			(layer "B.Fab")
		)
		(fp_line
			(start 0.67945 -0.305054)
			(end 0.12065 -0.305054)
			(stroke
				(width 0.1)
				(type default)
			)
			(layer "B.Fab")
		)
		(fp_line
			(start 0.12065 0.3048)
			(end 0.67945 0.3048)
			(stroke
				(width 0.1)
				(type default)
			)
			(layer "B.Fab")
		)
		(fp_line
			(start 0.12065 0.2794)
			(end 0.12065 0.3048)
			(stroke
				(width 0.1)
				(type default)
			)
			(layer "B.Fab")
		)
		(fp_line
			(start 0.12065 -0.2794)
			(end -0.12065 -0.2794)
			(stroke
				(width 0.1)
				(type default)
			)
			(layer "B.Fab")
		)
		(fp_line
			(start 0.12065 -0.305054)
			(end 0.12065 -0.2794)
			(stroke
				(width 0.1)
				(type default)
			)
			(layer "B.Fab")
		)
		(fp_line
			(start -0.120396 0.3048)
			(end -0.120396 0.2794)
			(stroke
				(width 0.1)
				(type default)
			)
			(layer "B.Fab")
		)
		(fp_line
			(start -0.120396 0.2794)
			(end 0.12065 0.2794)
			(stroke
				(width 0.1)
				(type default)
			)
			(layer "B.Fab")
		)
		(fp_line
			(start -0.12065 -0.2794)
			(end -0.12065 -0.3048)
			(stroke
				(width 0.1)
				(type default)
			)
			(layer "B.Fab")
		)
		(fp_line
			(start -0.12065 -0.3048)
			(end -0.67945 -0.3048)
			(stroke
				(width 0.1)
				(type default)
			)
			(layer "B.Fab")
		)
		(fp_line
			(start -0.67945 0.3048)
			(end -0.120396 0.3048)
			(stroke
				(width 0.1)
				(type default)
			)
			(layer "B.Fab")
		)
		(fp_line
			(start -0.67945 -0.3048)
			(end -0.67945 0.3048)
			(stroke
				(width 0.1)
				(type default)
			)
			(layer "B.Fab")
		)
		(pad "1" smd circle
			(at 0.40005 0)
			(size 0 0)
			(layers "B.Cu" "B.Mask" "B.Paste")
			(net "P1V8_AUX")
		)
		(pad "2" smd circle
			(at -0.40005 0)
			(size 0 0)
			(layers "B.Cu" "B.Mask" "B.Paste")
			(net "FM_SPD_CPU0_SWITCH_CTRL_N")
		)
	)
	(footprint ""
		(layer "B.Cu")
		(at 285.732982 -244.08511 180)
		(property "Reference" "R378"
			(at 0 0 0)
			(layer "B.SilkS")
			(hide yes)
			(effects
				(font
					(size 1.27 1.27)
				)
				(justify mirror)
			)
		)
		(property "Value" ""
			(at 0 0 0)
			(layer "B.Fab")
			(effects
				(font
					(size 1.27 1.27)
				)
				(justify mirror)
			)
		)
		(duplicate_pad_numbers_are_jumpers no)
		(fp_line
			(start 0.7874 0.4064)
			(end 0.7874 -0.4064)
			(stroke
				(width 0.1524)
				(type default)
			)
			(layer "B.SilkS")
		)
		(fp_line
			(start 0.7874 -0.4064)
			(end -0.7874 -0.4064)
			(stroke
				(width 0.1524)
				(type default)
			)
			(layer "B.SilkS")
		)
		(fp_line
			(start -0.7874 0.4064)
			(end 0.7874 0.4064)
			(stroke
				(width 0.1524)
				(type default)
			)
			(layer "B.SilkS")
		)
		(fp_line
			(start -0.7874 -0.4064)
			(end -0.7874 0.4064)
			(stroke
				(width 0.1524)
				(type default)
			)
			(layer "B.SilkS")
		)
		(fp_line
			(start 0.67945 0.3048)
			(end 0.67945 -0.305054)
			(stroke
				(width 0.1)
				(type default)
			)
			(layer "B.Fab")
		)
		(fp_line
			(start 0.67945 -0.305054)
			(end 0.12065 -0.305054)
			(stroke
				(width 0.1)
				(type default)
			)
			(layer "B.Fab")
		)
		(fp_line
			(start 0.12065 0.3048)
			(end 0.67945 0.3048)
			(stroke
				(width 0.1)
				(type default)
			)
			(layer "B.Fab")
		)
		(fp_line
			(start 0.12065 0.2794)
			(end 0.12065 0.3048)
			(stroke
				(width 0.1)
				(type default)
			)
			(layer "B.Fab")
		)
		(fp_line
			(start 0.12065 -0.2794)
			(end -0.12065 -0.2794)
			(stroke
				(width 0.1)
				(type default)
			)
			(layer "B.Fab")
		)
		(fp_line
			(start 0.12065 -0.305054)
			(end 0.12065 -0.2794)
			(stroke
				(width 0.1)
				(type default)
			)
			(layer "B.Fab")
		)
		(fp_line
			(start -0.120396 0.3048)
			(end -0.120396 0.2794)
			(stroke
				(width 0.1)
				(type default)
			)
			(layer "B.Fab")
		)
		(fp_line
			(start -0.120396 0.2794)
			(end 0.12065 0.2794)
			(stroke
				(width 0.1)
				(type default)
			)
			(layer "B.Fab")
		)
		(fp_line
			(start -0.12065 -0.2794)
			(end -0.12065 -0.3048)
			(stroke
				(width 0.1)
				(type default)
			)
			(layer "B.Fab")
		)
		(fp_line
			(start -0.12065 -0.3048)
			(end -0.67945 -0.3048)
			(stroke
				(width 0.1)
				(type default)
			)
			(layer "B.Fab")
		)
		(fp_line
			(start -0.67945 0.3048)
			(end -0.120396 0.3048)
			(stroke
				(width 0.1)
				(type default)
			)
			(layer "B.Fab")
		)
		(fp_line
			(start -0.67945 -0.3048)
			(end -0.67945 0.3048)
			(stroke
				(width 0.1)
				(type default)
			)
			(layer "B.Fab")
		)
		(pad "1" smd circle
			(at 0.40005 0)
			(size 0 0)
			(layers "B.Cu" "B.Mask" "B.Paste")
			(net "M_D_CPU0_ALERT_N")
		)
		(pad "2" smd circle
			(at -0.40005 0)
			(size 0 0)
			(layers "B.Cu" "B.Mask" "B.Paste")
			(net "M_D_CPU0_ALERT_R_N")
		)
	)
)
